(kicad_pcb
	(version 20221018)
	(generator pcbnew)
	(general
    (thickness 1.6)
  )
	(paper "A4")
	(title_block
    (title "NUC Computer Cluster Power Breakout HW")
    (date "2023-10-18")
    (rev "1.4.3")
    (company "Antmicro Ltd.")
		(comment 9 "footprints 85-91 of 234")
	)
	(layers
    (0 "F.Cu" mixed)
    (1 "In1.Cu" power)
    (2 "In2.Cu" mixed)
    (31 "B.Cu" power)
    (32 "B.Adhes" user "B.Adhesive")
    (33 "F.Adhes" user "F.Adhesive")
    (34 "B.Paste" user)
    (35 "F.Paste" user)
    (36 "B.SilkS" user "B.Silkscreen")
    (37 "F.SilkS" user "F.Silkscreen")
    (38 "B.Mask" user)
    (39 "F.Mask" user)
    (40 "Dwgs.User" user "User.Drawings")
    (41 "Cmts.User" user "User.Comments")
    (42 "Eco1.User" user "User.Eco1")
    (43 "Eco2.User" user "User.Eco2")
    (44 "Edge.Cuts" user)
    (45 "Margin" user)
    (46 "B.CrtYd" user "B.Courtyard")
    (47 "F.CrtYd" user "F.Courtyard")
    (48 "B.Fab" user)
    (49 "F.Fab" user)
  )
	(footprint "antmicro-footprints:TP_SMD_1mm" (layer "F.Cu")
    (at 116.9 131.4 -90)
    (property "Author" "Antmicro")
    (property "License" "Apache-2.0")
    (property "MPN" "")
    (property "Manufacturer" "")
    (property "Sheetfile" "d1600e-psu-breakout-board.kicad_sch")
    (property "Sheetname" "")
    (property "exclude_from_bom" "")
    (property "ki_description" "Test point 1mm SMD")
    (property "ki_keywords" "TESTPOINT")
    (attr exclude_from_pos_files exclude_from_bom)
    (fp_text reference "TP_S19" (at -0.7 -0.45 -90) (layer "F.SilkS")
        (effects (font (size 0.7 0.7) (thickness 0.15)) (justify left bottom))
    )
    (fp_text value "TP_1mm_SMD" (at 0 1.4 -90) (layer "F.Fab")
        (effects (font (size 0.7 0.7) (thickness 0.15)) (justify left bottom))
    )
    (fp_text user "License: Apache-2.0" (at -0.5 5.2 -90) (layer "F.Fab") hide
        (effects (font (size 0.7 0.7) (thickness 0.15)) (justify left bottom))
    )
    (fp_text user "Author: Antmicro" (at -0.5 4 -90) (layer "F.Fab") hide
        (effects (font (size 0.7 0.7) (thickness 0.15)) (justify left bottom))
    )
    (fp_text user "${REFERENCE}" (at -0.5 2.8 -90) (layer "F.Fab") hide
        (effects (font (size 0.7 0.7) (thickness 0.15)) (justify left bottom))
    )
    (fp_circle (center 0 0) (end 0.6 0)
      (stroke (width 0.05) (type default)) (fill none) (layer "F.CrtYd"))
    (pad "1" smd circle (at 0 0 270) (size 1 1) (layers "F.Cu" "F.Mask")
      (net 71 "Net-(J10-PadS19)") (pinfunction "1") (pintype "passive"))
  )
	(footprint "antmicro-footprints:TP_SMD_1mm" (layer "F.Cu")
    (at 118.2 131.4 -90)
    (property "Author" "Antmicro")
    (property "License" "Apache-2.0")
    (property "MPN" "")
    (property "Manufacturer" "")
    (property "Sheetfile" "d1600e-psu-breakout-board.kicad_sch")
    (property "Sheetname" "")
    (property "exclude_from_bom" "")
    (property "ki_description" "Test point 1mm SMD")
    (property "ki_keywords" "TESTPOINT")
    (attr exclude_from_pos_files exclude_from_bom)
    (fp_text reference "TP_S20" (at -0.7 -0.45 -90) (layer "F.SilkS")
        (effects (font (size 0.7 0.7) (thickness 0.15)) (justify left bottom))
    )
    (fp_text value "TP_1mm_SMD" (at 0 1.4 -90) (layer "F.Fab")
        (effects (font (size 0.7 0.7) (thickness 0.15)) (justify left bottom))
    )
    (fp_text user "Author: Antmicro" (at -0.5 4 -90) (layer "F.Fab") hide
        (effects (font (size 0.7 0.7) (thickness 0.15)) (justify left bottom))
    )
    (fp_text user "${REFERENCE}" (at -0.5 2.8 -90) (layer "F.Fab") hide
        (effects (font (size 0.7 0.7) (thickness 0.15)) (justify left bottom))
    )
    (fp_text user "License: Apache-2.0" (at -0.5 5.2 -90) (layer "F.Fab") hide
        (effects (font (size 0.7 0.7) (thickness 0.15)) (justify left bottom))
    )
    (fp_circle (center 0 0) (end 0.6 0)
      (stroke (width 0.05) (type default)) (fill none) (layer "F.CrtYd"))
    (pad "1" smd circle (at 0 0 270) (size 1 1) (layers "F.Cu" "F.Mask")
      (net 74 "Net-(J10-PadS20)") (pinfunction "1") (pintype "passive"))
  )
	(footprint "antmicro-footprints:TP_SMD_1mm" (layer "F.Cu")
    (at 119.5 131.4 -90)
    (property "Author" "Antmicro")
    (property "License" "Apache-2.0")
    (property "MPN" "")
    (property "Manufacturer" "")
    (property "Sheetfile" "d1600e-psu-breakout-board.kicad_sch")
    (property "Sheetname" "")
    (property "exclude_from_bom" "")
    (property "ki_description" "Test point 1mm SMD")
    (property "ki_keywords" "TESTPOINT")
    (attr exclude_from_pos_files exclude_from_bom)
    (fp_text reference "TP_S21" (at -0.7 -0.45 -90) (layer "F.SilkS")
        (effects (font (size 0.7 0.7) (thickness 0.15)) (justify left bottom))
    )
    (fp_text value "TP_1mm_SMD" (at 0 1.4 -90) (layer "F.Fab")
        (effects (font (size 0.7 0.7) (thickness 0.15)) (justify left bottom))
    )
    (fp_text user "Author: Antmicro" (at -0.5 4 -90) (layer "F.Fab") hide
        (effects (font (size 0.7 0.7) (thickness 0.15)) (justify left bottom))
    )
    (fp_text user "${REFERENCE}" (at -0.5 2.8 -90) (layer "F.Fab") hide
        (effects (font (size 0.7 0.7) (thickness 0.15)) (justify left bottom))
    )
    (fp_text user "License: Apache-2.0" (at -0.5 5.2 -90) (layer "F.Fab") hide
        (effects (font (size 0.7 0.7) (thickness 0.15)) (justify left bottom))
    )
    (fp_circle (center 0 0) (end 0.6 0)
      (stroke (width 0.05) (type default)) (fill none) (layer "F.CrtYd"))
    (pad "1" smd circle (at 0 0 270) (size 1 1) (layers "F.Cu" "F.Mask")
      (net 69 "Net-(J10-PadS21)") (pinfunction "1") (pintype "passive"))
  )
	(footprint "antmicro-footprints:TP_SMD_1mm" (layer "F.Cu")
    (at 123.4508 131.4 -90)
    (property "Author" "Antmicro")
    (property "License" "Apache-2.0")
    (property "MPN" "")
    (property "Manufacturer" "")
    (property "Sheetfile" "d1600e-psu-breakout-board.kicad_sch")
    (property "Sheetname" "")
    (property "exclude_from_bom" "")
    (property "ki_description" "Test point 1mm SMD")
    (property "ki_keywords" "TESTPOINT")
    (attr exclude_from_pos_files exclude_from_bom)
    (fp_text reference "TP_S24" (at -0.7 -0.45 -90) (layer "F.SilkS")
        (effects (font (size 0.7 0.7) (thickness 0.15)) (justify left bottom))
    )
    (fp_text value "TP_1mm_SMD" (at 0 1.4 -90) (layer "F.Fab")
        (effects (font (size 0.7 0.7) (thickness 0.15)) (justify left bottom))
    )
    (fp_text user "License: Apache-2.0" (at -0.5 5.2 -90) (layer "F.Fab") hide
        (effects (font (size 0.7 0.7) (thickness 0.15)) (justify left bottom))
    )
    (fp_text user "${REFERENCE}" (at -0.5 2.8 -90) (layer "F.Fab") hide
        (effects (font (size 0.7 0.7) (thickness 0.15)) (justify left bottom))
    )
    (fp_text user "Author: Antmicro" (at -0.5 4 -90) (layer "F.Fab") hide
        (effects (font (size 0.7 0.7) (thickness 0.15)) (justify left bottom))
    )
    (fp_circle (center 0 0) (end 0.6 0)
      (stroke (width 0.05) (type default)) (fill none) (layer "F.CrtYd"))
    (pad "1" smd circle (at 0 0 270) (size 1 1) (layers "F.Cu" "F.Mask")
      (net 55 "Net-(J10-PadS24)") (pinfunction "1") (pintype "passive"))
  )
	(footprint "antmicro-footprints:TP_SMD_1mm" (layer "F.Cu")
    (at 110.25 137.4)
    (property "Author" "Antmicro")
    (property "License" "Apache-2.0")
    (property "MPN" "")
    (property "Manufacturer" "")
    (property "Sheetfile" "d1600e-psu-breakout-board.kicad_sch")
    (property "Sheetname" "")
    (property "exclude_from_bom" "")
    (property "ki_description" "Test point 1mm SMD")
    (property "ki_keywords" "TESTPOINT")
    (attr exclude_from_pos_files exclude_from_bom)
    (fp_text reference "TP_S11" (at 0.311136 -0.412467 90) (layer "F.SilkS")
        (effects (font (size 0.7 0.7) (thickness 0.15)) (justify left bottom))
    )
    (fp_text value "TP_1mm_SMD" (at 0 1.4) (layer "F.Fab")
        (effects (font (size 0.7 0.7) (thickness 0.15)) (justify left bottom))
    )
    (fp_text user "License: Apache-2.0" (at -0.5 5.2) (layer "F.Fab") hide
        (effects (font (size 0.7 0.7) (thickness 0.15)) (justify left bottom))
    )
    (fp_text user "Author: Antmicro" (at -0.5 4) (layer "F.Fab") hide
        (effects (font (size 0.7 0.7) (thickness 0.15)) (justify left bottom))
    )
    (fp_text user "${REFERENCE}" (at -0.5 2.8) (layer "F.Fab") hide
        (effects (font (size 0.7 0.7) (thickness 0.15)) (justify left bottom))
    )
    (fp_circle (center 0 0) (end 0.6 0)
      (stroke (width 0.05) (type default)) (fill none) (layer "F.CrtYd"))
    (pad "1" smd circle (at 0 0) (size 1 1) (layers "F.Cu" "F.Mask")
      (net 57 "Net-(J10-PadS11)") (pinfunction "1") (pintype "passive"))
  )
	(footprint "antmicro-footprints:TP_SMD_1mm" (layer "F.Cu")
    (at 108.9 137.4508)
    (property "Author" "Antmicro")
    (property "License" "Apache-2.0")
    (property "MPN" "")
    (property "Manufacturer" "")
    (property "Sheetfile" "d1600e-psu-breakout-board.kicad_sch")
    (property "Sheetname" "")
    (property "exclude_from_bom" "")
    (property "ki_description" "Test point 1mm SMD")
    (property "ki_keywords" "TESTPOINT")
    (attr exclude_from_pos_files exclude_from_bom)
    (fp_text reference "TP_S12" (at -0.15 -2.5016 90) (layer "F.SilkS")
        (effects (font (size 0.7 0.7) (thickness 0.15)))
    )
    (fp_text value "TP_1mm_SMD" (at 0 1.4) (layer "F.Fab")
        (effects (font (size 0.7 0.7) (thickness 0.15)) (justify left bottom))
    )
    (fp_text user "${REFERENCE}" (at -0.5 2.8) (layer "F.Fab") hide
        (effects (font (size 0.7 0.7) (thickness 0.15)) (justify left bottom))
    )
    (fp_text user "License: Apache-2.0" (at -0.5 5.2) (layer "F.Fab") hide
        (effects (font (size 0.7 0.7) (thickness 0.15)) (justify left bottom))
    )
    (fp_text user "Author: Antmicro" (at -0.5 4) (layer "F.Fab") hide
        (effects (font (size 0.7 0.7) (thickness 0.15)) (justify left bottom))
    )
    (fp_circle (center 0 0) (end 0.6 0)
      (stroke (width 0.05) (type default)) (fill none) (layer "F.CrtYd"))
    (pad "1" smd circle (at 0 0) (size 1 1) (layers "F.Cu" "F.Mask")
      (net 56 "Net-(J10-PadS12)") (pinfunction "1") (pintype "passive"))
  )
	(footprint "antmicro-footprints:TP_SMD_1mm" (layer "F.Cu")
    (at 122.1508 131.4 -90)
    (property "Author" "Antmicro")
    (property "License" "Apache-2.0")
    (property "MPN" "")
    (property "Manufacturer" "")
    (property "Sheetfile" "d1600e-psu-breakout-board.kicad_sch")
    (property "Sheetname" "")
    (property "exclude_from_bom" "")
    (property "ki_description" "Test point 1mm SMD")
    (property "ki_keywords" "TESTPOINT")
    (attr exclude_from_pos_files exclude_from_bom)
    (fp_text reference "TP_S23" (at -0.7 -0.45 -90) (layer "F.SilkS")
        (effects (font (size 0.7 0.7) (thickness 0.15)) (justify left bottom))
    )
    (fp_text value "TP_1mm_SMD" (at 0 1.4 -90) (layer "F.Fab")
        (effects (font (size 0.7 0.7) (thickness 0.15)) (justify left bottom))
    )
    (fp_text user "${REFERENCE}" (at -0.5 2.8 -90) (layer "F.Fab") hide
        (effects (font (size 0.7 0.7) (thickness 0.15)) (justify left bottom))
    )
    (fp_text user "Author: Antmicro" (at -0.5 4 -90) (layer "F.Fab") hide
        (effects (font (size 0.7 0.7) (thickness 0.15)) (justify left bottom))
    )
    (fp_text user "License: Apache-2.0" (at -0.5 5.2 -90) (layer "F.Fab") hide
        (effects (font (size 0.7 0.7) (thickness 0.15)) (justify left bottom))
    )
    (fp_circle (center 0 0) (end 0.6 0)
      (stroke (width 0.05) (type default)) (fill none) (layer "F.CrtYd"))
    (pad "1" smd circle (at 0 0 270) (size 1 1) (layers "F.Cu" "F.Mask")
      (net 68 "Net-(J10-PadS23)") (pinfunction "1") (pintype "passive"))
  )
)
